# S9S_MB_2U (Grand Teton) — schematic netlist excerpt (pin names and nets, part order shuffled) for the footprints in the layout excerpt that follows; sources: Cadence DE-HDL packaged netlist, KiCad conversion of 03242023_DA0F0TMBIJ0_F0T_Motherboard_J_brd_V01_OCP.brd

R4713  Q_RES  100K 1% CHIP  pkg 0402LF  page 185 : A = RST_PFR_OVR_SRTC ; B = GND
PR274  Q_RES  0 5% CHIP  pkg 0402LF  page 292 : A = SH_PVCCFA_EHV_CPU1 ; B = SH_PVCCFA_EHV_CPU1_R
PC570  Q_CAP  22UF 16V 20% X6S  pkg C0805  page 259 : A = SW_P3V3_AUX_FLT ; B = GND

(kicad_pcb
	(version 20260206)
	(generator "pcbnew")
	(generator_version "10.0")
	(general
		(thickness 1.6)
		(legacy_teardrops no)
	)
	(paper "A4")
	(title_block
		(title "03242023_DA0F0TMBIJ0_F0T_Motherboard_J_brd_V01_OCP.brd")
		(comment 1 "Grand Teton / footprints 3537-3539 of 6105")
	)
	(layers
		(0 "F.Cu" signal "TOP")
		(4 "In1.Cu" signal "GND")
		(6 "In2.Cu" signal "IN1")
		(8 "In3.Cu" signal "GND1")
		(10 "In4.Cu" signal "IN2")
		(12 "In5.Cu" signal "GND2")
		(14 "In6.Cu" signal "IN3")
		(16 "In7.Cu" signal "GND3")
		(18 "In8.Cu" signal "VCC")
		(20 "In9.Cu" signal "VCC1")
		(22 "In10.Cu" signal "GND4")
		(24 "In11.Cu" signal "IN4")
		(26 "In12.Cu" signal "GND5")
		(28 "In13.Cu" signal "IN5")
		(30 "In14.Cu" signal "GND6")
		(32 "In15.Cu" signal "IN6")
		(34 "In16.Cu" signal "GND7")
		(2 "B.Cu" signal "BOTTOM")
		(9 "F.Adhes" user "F.Adhesive")
		(11 "B.Adhes" user "B.Adhesive")
		(13 "F.Paste" user "Package Geometry/Pastemask Top")
		(15 "B.Paste" user "Package Geometry/Pastemask Bottom")
		(5 "F.SilkS" user "Ref Des/Silkscreen Top")
		(7 "B.SilkS" user "Ref Des/Silkscreen Bottom")
		(1 "F.Mask" user "Board Geometry/Soldermask Top")
		(3 "B.Mask" user "Board Geometry/Soldermask Bottom")
		(17 "Dwgs.User" user "User.Drawings")
		(19 "Cmts.User" user "User.Comments")
		(21 "Eco1.User" user "User.Eco1")
		(23 "Eco2.User" user "User.Eco2")
		(25 "Edge.Cuts" user "Board Geometry/Outline")
		(27 "Margin" user)
		(31 "F.CrtYd" user "Package Geometry/Place Bound Top")
		(29 "B.CrtYd" user "Package Geometry/Place Bound Bottom")
		(35 "F.Fab" user "Ref Des/Assembly Top")
		(33 "B.Fab" user "Ref Des/Assembly Bottom")
	)
	(footprint ""
		(layer "F.Cu")
		(at 27.595322 -133.430518 -90)
		(property "Reference" "PR274"
			(at 0 0 270)
			(layer "F.SilkS")
			(hide yes)
			(effects
				(font
					(size 1.27 1.27)
				)
			)
		)
		(property "Value" ""
			(at 0 0 270)
			(layer "F.Fab")
			(effects
				(font
					(size 1.27 1.27)
				)
			)
		)
		(duplicate_pad_numbers_are_jumpers no)
		(fp_line
			(start -0.7874 0.4064)
			(end -0.7874 -0.4064)
			(stroke
				(width 0.1524)
				(type default)
			)
			(layer "F.SilkS")
		)
		(fp_line
			(start 0.7874 0.4064)
			(end -0.7874 0.4064)
			(stroke
				(width 0.1524)
				(type default)
			)
			(layer "F.SilkS")
		)
		(fp_line
			(start -0.7874 -0.4064)
			(end 0.7874 -0.4064)
			(stroke
				(width 0.1524)
				(type default)
			)
			(layer "F.SilkS")
		)
		(fp_line
			(start 0.7874 -0.4064)
			(end 0.7874 0.4064)
			(stroke
				(width 0.1524)
				(type default)
			)
			(layer "F.SilkS")
		)
		(fp_line
			(start -0.67945 0.3048)
			(end -0.67945 -0.305054)
			(stroke
				(width 0.1)
				(type default)
			)
			(layer "F.Fab")
		)
		(fp_line
			(start -0.12065 0.3048)
			(end -0.67945 0.3048)
			(stroke
				(width 0.1)
				(type default)
			)
			(layer "F.Fab")
		)
		(fp_line
			(start 0.120396 0.3048)
			(end 0.120396 0.2794)
			(stroke
				(width 0.1)
				(type default)
			)
			(layer "F.Fab")
		)
		(fp_line
			(start 0.67945 0.3048)
			(end 0.120396 0.3048)
			(stroke
				(width 0.1)
				(type default)
			)
			(layer "F.Fab")
		)
		(fp_line
			(start -0.12065 0.2794)
			(end -0.12065 0.3048)
			(stroke
				(width 0.1)
				(type default)
			)
			(layer "F.Fab")
		)
		(fp_line
			(start 0.120396 0.2794)
			(end -0.12065 0.2794)
			(stroke
				(width 0.1)
				(type default)
			)
			(layer "F.Fab")
		)
		(fp_line
			(start -0.12065 -0.2794)
			(end 0.12065 -0.2794)
			(stroke
				(width 0.1)
				(type default)
			)
			(layer "F.Fab")
		)
		(fp_line
			(start 0.12065 -0.2794)
			(end 0.12065 -0.3048)
			(stroke
				(width 0.1)
				(type default)
			)
			(layer "F.Fab")
		)
		(fp_line
			(start 0.12065 -0.3048)
			(end 0.67945 -0.3048)
			(stroke
				(width 0.1)
				(type default)
			)
			(layer "F.Fab")
		)
		(fp_line
			(start 0.67945 -0.3048)
			(end 0.67945 0.3048)
			(stroke
				(width 0.1)
				(type default)
			)
			(layer "F.Fab")
		)
		(fp_line
			(start -0.67945 -0.305054)
			(end -0.12065 -0.305054)
			(stroke
				(width 0.1)
				(type default)
			)
			(layer "F.Fab")
		)
		(fp_line
			(start -0.12065 -0.305054)
			(end -0.12065 -0.2794)
			(stroke
				(width 0.1)
				(type default)
			)
			(layer "F.Fab")
		)
		(pad "1" smd circle
			(at -0.40005 0 270)
			(size 0 0)
			(layers "F.Cu" "F.Mask" "F.Paste")
			(net "SH_PVCCFA_EHV_CPU1")
		)
		(pad "2" smd circle
			(at 0.40005 0 270)
			(size 0 0)
			(layers "F.Cu" "F.Mask" "F.Paste")
			(net "SH_PVCCFA_EHV_CPU1_R")
		)
	)
	(footprint ""
		(layer "F.Cu")
		(at 202.322684 -105.315004 90)
		(property "Reference" "R4713"
			(at 0 0 90)
			(layer "F.SilkS")
			(hide yes)
			(effects
				(font
					(size 1.27 1.27)
				)
			)
		)
		(property "Value" ""
			(at 0 0 90)
			(layer "F.Fab")
			(effects
				(font
					(size 1.27 1.27)
				)
			)
		)
		(duplicate_pad_numbers_are_jumpers no)
		(fp_line
			(start 0.7874 -0.4064)
			(end 0.7874 0.4064)
			(stroke
				(width 0.1524)
				(type default)
			)
			(layer "F.SilkS")
		)
		(fp_line
			(start -0.7874 -0.4064)
			(end 0.7874 -0.4064)
			(stroke
				(width 0.1524)
				(type default)
			)
			(layer "F.SilkS")
		)
		(fp_line
			(start 0.7874 0.4064)
			(end -0.7874 0.4064)
			(stroke
				(width 0.1524)
				(type default)
			)
			(layer "F.SilkS")
		)
		(fp_line
			(start -0.7874 0.4064)
			(end -0.7874 -0.4064)
			(stroke
				(width 0.1524)
				(type default)
			)
			(layer "F.SilkS")
		)
		(fp_line
			(start -0.12065 -0.305054)
			(end -0.12065 -0.2794)
			(stroke
				(width 0.1)
				(type default)
			)
			(layer "F.Fab")
		)
		(fp_line
			(start -0.67945 -0.305054)
			(end -0.12065 -0.305054)
			(stroke
				(width 0.1)
				(type default)
			)
			(layer "F.Fab")
		)
		(fp_line
			(start 0.67945 -0.3048)
			(end 0.67945 0.3048)
			(stroke
				(width 0.1)
				(type default)
			)
			(layer "F.Fab")
		)
		(fp_line
			(start 0.12065 -0.3048)
			(end 0.67945 -0.3048)
			(stroke
				(width 0.1)
				(type default)
			)
			(layer "F.Fab")
		)
		(fp_line
			(start 0.12065 -0.2794)
			(end 0.12065 -0.3048)
			(stroke
				(width 0.1)
				(type default)
			)
			(layer "F.Fab")
		)
		(fp_line
			(start -0.12065 -0.2794)
			(end 0.12065 -0.2794)
			(stroke
				(width 0.1)
				(type default)
			)
			(layer "F.Fab")
		)
		(fp_line
			(start 0.120396 0.2794)
			(end -0.12065 0.2794)
			(stroke
				(width 0.1)
				(type default)
			)
			(layer "F.Fab")
		)
		(fp_line
			(start -0.12065 0.2794)
			(end -0.12065 0.3048)
			(stroke
				(width 0.1)
				(type default)
			)
			(layer "F.Fab")
		)
		(fp_line
			(start 0.67945 0.3048)
			(end 0.120396 0.3048)
			(stroke
				(width 0.1)
				(type default)
			)
			(layer "F.Fab")
		)
		(fp_line
			(start 0.120396 0.3048)
			(end 0.120396 0.2794)
			(stroke
				(width 0.1)
				(type default)
			)
			(layer "F.Fab")
		)
		(fp_line
			(start -0.12065 0.3048)
			(end -0.67945 0.3048)
			(stroke
				(width 0.1)
				(type default)
			)
			(layer "F.Fab")
		)
		(fp_line
			(start -0.67945 0.3048)
			(end -0.67945 -0.305054)
			(stroke
				(width 0.1)
				(type default)
			)
			(layer "F.Fab")
		)
		(pad "1" smd circle
			(at -0.40005 0 90)
			(size 0 0)
			(layers "F.Cu" "F.Mask" "F.Paste")
			(net "RST_PFR_OVR_SRTC")
		)
		(pad "2" smd circle
			(at 0.40005 0 90)
			(size 0 0)
			(layers "F.Cu" "F.Mask" "F.Paste")
			(net "GND")
		)
	)
	(footprint ""
		(layer "F.Cu")
		(at 453.345804 -71.245984 -90)
		(property "Reference" "PC570"
			(at 0 0 270)
			(layer "F.SilkS")
			(hide yes)
			(effects
				(font
					(size 1.27 1.27)
				)
			)
		)
		(property "Value" ""
			(at 0 0 270)
			(layer "F.Fab")
			(effects
				(font
					(size 1.27 1.27)
				)
			)
		)
		(duplicate_pad_numbers_are_jumpers no)
		(fp_line
			(start -1.524 0.762)
			(end -1.524 -0.762)
			(stroke
				(width 0.1524)
				(type default)
			)
			(layer "F.SilkS")
		)
		(fp_line
			(start 1.524 0.762)
			(end -1.524 0.762)
			(stroke
				(width 0.1524)
				(type default)
			)
			(layer "F.SilkS")
		)
		(fp_line
			(start -1.524 -0.762)
			(end 1.524 -0.762)
			(stroke
				(width 0.1524)
				(type default)
			)
			(layer "F.SilkS")
		)
		(fp_line
			(start 1.524 -0.762)
			(end 1.524 0.762)
			(stroke
				(width 0.1524)
				(type default)
			)
			(layer "F.SilkS")
		)
		(fp_line
			(start -1.1049 0.724916)
			(end 1.1049 0.724916)
			(stroke
				(width 0.1)
				(type default)
			)
			(layer "F.Fab")
		)
		(fp_line
			(start 1.1049 0.724916)
			(end 1.1049 -0.724916)
			(stroke
				(width 0.1)
				(type default)
			)
			(layer "F.Fab")
		)
		(fp_line
			(start -1.1049 -0.724916)
			(end -1.1049 0.724916)
			(stroke
				(width 0.1)
				(type default)
			)
			(layer "F.Fab")
		)
		(fp_line
			(start 1.1049 -0.724916)
			(end -1.1049 -0.724916)
			(stroke
				(width 0.1)
				(type default)
			)
			(layer "F.Fab")
		)
		(pad "1" smd rect
			(at -0.889 0 90)
			(size 1.016 1.27)
			(layers "F.Cu" "F.Mask" "F.Paste")
			(net "SW_P3V3_AUX_FLT")
		)
		(pad "2" smd rect
			(at 0.889 0 90)
			(size 1.016 1.27)
			(layers "F.Cu" "F.Mask" "F.Paste")
			(net "GND")
		)
	)
)
